# T6G (Grand Teton) — schematic netlist excerpt (pin names and nets, part order shuffled) for the footprints in the layout excerpt that follows; sources: Cadence DE-HDL packaged netlist, KiCad conversion of 04192023_DAF0TMB3IC0_F0TG_MB_C_brd_V02_OCP.brd

R5101  Q_RES  10K 5% CHIP  pkg 0402LF  page 187 : A = P3V3_AUX ; B = P3V3_STBY_R

U316  74LVC2G17GW  IC  pkg SOT363  page 124
  A0  = SWB_HSC_EN
  GND  = GND
  A1  = GND
  B1  = NC_U316_2Y
  VCC  = P3V3_AUX
  B0  = SWB_HSC_EN_BUF_R

(kicad_pcb
	(version 20260206)
	(generator "pcbnew")
	(generator_version "10.0")
	(general
		(thickness 1.6)
		(legacy_teardrops no)
	)
	(paper "A4")
	(title_block
		(title "04192023_DAF0TMB3IC0_F0TG_MB_C_brd_V02_OCP.brd")
		(comment 1 "Grand Teton / footprints 2848-2849 of 8354")
	)
	(layers
		(0 "F.Cu" signal "TOP")
		(4 "In1.Cu" signal "GND")
		(6 "In2.Cu" signal "IN1")
		(8 "In3.Cu" signal "GND1")
		(10 "In4.Cu" signal "IN2")
		(12 "In5.Cu" signal "GND2")
		(14 "In6.Cu" signal "IN3")
		(16 "In7.Cu" signal "GND3")
		(18 "In8.Cu" signal "VCC")
		(20 "In9.Cu" signal "VCC1")
		(22 "In10.Cu" signal "GND4")
		(24 "In11.Cu" signal "IN4")
		(26 "In12.Cu" signal "GND5")
		(28 "In13.Cu" signal "IN5")
		(30 "In14.Cu" signal "GND6")
		(32 "In15.Cu" signal "IN6")
		(34 "In16.Cu" signal "GND7")
		(2 "B.Cu" signal "BOTTOM")
		(9 "F.Adhes" user "F.Adhesive")
		(11 "B.Adhes" user "B.Adhesive")
		(13 "F.Paste" user "Package Geometry/Pastemask Top")
		(15 "B.Paste" user "Package Geometry/Pastemask Bottom")
		(5 "F.SilkS" user "Ref Des/Silkscreen Top")
		(7 "B.SilkS" user "Ref Des/Silkscreen Bottom")
		(1 "F.Mask" user "Board Geometry/Soldermask Top")
		(3 "B.Mask" user "Board Geometry/Soldermask Bottom")
		(17 "Dwgs.User" user "User.Drawings")
		(19 "Cmts.User" user "User.Comments")
		(21 "Eco1.User" user "User.Eco1")
		(23 "Eco2.User" user "User.Eco2")
		(25 "Edge.Cuts" user "Board Geometry/Outline")
		(27 "Margin" user)
		(31 "F.CrtYd" user "Package Geometry/Place Bound Top")
		(29 "B.CrtYd" user "Package Geometry/Place Bound Bottom")
		(35 "F.Fab" user "Ref Des/Assembly Top")
		(33 "B.Fab" user "Ref Des/Assembly Bottom")
	)
	(footprint ""
		(layer "F.Cu")
		(at 352.45548 -436.925212 -90)
		(property "Reference" "U316"
			(at 1.614424 -1.87071 90)
			(unlocked yes)
			(layer "F.SilkS")
			(effects
				(font
					(size 0.7874 0.5842)
					(thickness 0.1524)
				)
				(justify left)
			)
		)
		(property "Value" ""
			(at 0 0 270)
			(layer "F.Fab")
			(effects
				(font
					(size 1.27 1.27)
				)
			)
		)
		(duplicate_pad_numbers_are_jumpers no)
		(fp_line
			(start -1.3462 1.100074)
			(end -1.3462 -1.100074)
			(stroke
				(width 0.1524)
				(type default)
			)
			(layer "F.SilkS")
		)
		(fp_line
			(start 1.3462 1.100074)
			(end -1.3462 1.100074)
			(stroke
				(width 0.1524)
				(type default)
			)
			(layer "F.SilkS")
		)
		(fp_line
			(start 0 -0.381)
			(end 0.670052 -1.100074)
			(stroke
				(width 0.1524)
				(type default)
			)
			(layer "F.SilkS")
		)
		(fp_line
			(start -1.3462 -1.100074)
			(end -0.670052 -1.100074)
			(stroke
				(width 0.1524)
				(type default)
			)
			(layer "F.SilkS")
		)
		(fp_line
			(start -0.670052 -1.100074)
			(end 0 -0.381)
			(stroke
				(width 0.1524)
				(type default)
			)
			(layer "F.SilkS")
		)
		(fp_line
			(start 0.670052 -1.100074)
			(end 1.3462 -1.100074)
			(stroke
				(width 0.1524)
				(type default)
			)
			(layer "F.SilkS")
		)
		(fp_line
			(start 1.3462 -1.100074)
			(end 1.3462 1.100074)
			(stroke
				(width 0.1524)
				(type default)
			)
			(layer "F.SilkS")
		)
		(fp_poly
			(pts
				(xy -2.29108 -1.452372) (xy -1.752346 -1.991106) (xy -1.482852 -1.182878)
			)
			(stroke
				(width 0)
				(type default)
			)
			(fill yes)
			(layer "F.SilkS")
		)
		(fp_line
			(start -0.670052 1.100074)
			(end -0.670052 0.8001)
			(stroke
				(width 0.1)
				(type default)
			)
			(layer "F.Fab")
		)
		(fp_line
			(start 0.670052 1.100074)
			(end -0.670052 1.100074)
			(stroke
				(width 0.1)
				(type default)
			)
			(layer "F.Fab")
		)
		(fp_line
			(start -1.100074 0.8001)
			(end -1.100074 -0.8001)
			(stroke
				(width 0.1)
				(type default)
			)
			(layer "F.Fab")
		)
		(fp_line
			(start -0.670052 0.8001)
			(end -1.100074 0.8001)
			(stroke
				(width 0.1)
				(type default)
			)
			(layer "F.Fab")
		)
		(fp_line
			(start -0.670052 0.8001)
			(end -0.670052 -0.8001)
			(stroke
				(width 0.1)
				(type default)
			)
			(layer "F.Fab")
		)
		(fp_line
			(start 0.670052 0.8001)
			(end 0.670052 1.100074)
			(stroke
				(width 0.1)
				(type default)
			)
			(layer "F.Fab")
		)
		(fp_line
			(start 1.100074 0.8001)
			(end 0.670052 0.8001)
			(stroke
				(width 0.1)
				(type default)
			)
			(layer "F.Fab")
		)
		(fp_line
			(start -1.100074 -0.8001)
			(end -0.670052 -0.8001)
			(stroke
				(width 0.1)
				(type default)
			)
			(layer "F.Fab")
		)
		(fp_line
			(start -0.670052 -0.8001)
			(end -0.670052 -1.100074)
			(stroke
				(width 0.1)
				(type default)
			)
			(layer "F.Fab")
		)
		(fp_line
			(start 0.670052 -0.8001)
			(end 0.670052 0.8001)
			(stroke
				(width 0.1)
				(type default)
			)
			(layer "F.Fab")
		)
		(fp_line
			(start 0.670052 -0.8001)
			(end 1.100074 -0.8001)
			(stroke
				(width 0.1)
				(type default)
			)
			(layer "F.Fab")
		)
		(fp_line
			(start 1.100074 -0.8001)
			(end 1.100074 0.8001)
			(stroke
				(width 0.1)
				(type default)
			)
			(layer "F.Fab")
		)
		(fp_line
			(start -0.670052 -1.100074)
			(end 0.670052 -1.100074)
			(stroke
				(width 0.1)
				(type default)
			)
			(layer "F.Fab")
		)
		(fp_line
			(start 0.670052 -1.100074)
			(end 0.670052 -0.8001)
			(stroke
				(width 0.1)
				(type default)
			)
			(layer "F.Fab")
		)
		(fp_poly
			(pts
				(xy -1.524 -0.649986) (xy -2.286 -1.030986) (xy -2.286 -0.268986)
			)
			(stroke
				(width 0)
				(type default)
			)
			(fill yes)
			(layer "F.Fab")
		)
		(pad "1" smd rect
			(at -0.94996 -0.649986 180)
			(size 0.4064 0.508)
			(layers "F.Cu" "F.Mask" "F.Paste")
			(net "SWB_HSC_EN")
		)
		(pad "2" smd rect
			(at -0.94996 0 180)
			(size 0.4064 0.508)
			(layers "F.Cu" "F.Mask" "F.Paste")
			(net "GND")
		)
		(pad "3" smd rect
			(at -0.94996 0.649986 180)
			(size 0.4064 0.508)
			(layers "F.Cu" "F.Mask" "F.Paste")
			(net "GND")
		)
		(pad "4" smd rect
			(at 0.94996 0.649986 180)
			(size 0.4064 0.508)
			(layers "F.Cu" "F.Mask" "F.Paste")
			(net "NC_U316_2Y")
		)
		(pad "5" smd rect
			(at 0.94996 0 180)
			(size 0.4064 0.508)
			(layers "F.Cu" "F.Mask" "F.Paste")
			(net "P3V3_AUX")
		)
		(pad "6" smd rect
			(at 0.94996 -0.649986 180)
			(size 0.4064 0.508)
			(layers "F.Cu" "F.Mask" "F.Paste")
			(net "SWB_HSC_EN_BUF_R")
		)
	)
	(footprint ""
		(layer "F.Cu")
		(at 305.754024 -32.701992)
		(property "Reference" "R5101"
			(at 0 0 0)
			(layer "F.SilkS")
			(hide yes)
			(effects
				(font
					(size 1.27 1.27)
				)
			)
		)
		(property "Value" ""
			(at 0 0 0)
			(layer "F.Fab")
			(effects
				(font
					(size 1.27 1.27)
				)
			)
		)
		(duplicate_pad_numbers_are_jumpers no)
		(fp_line
			(start -0.7874 -0.4064)
			(end 0.7874 -0.4064)
			(stroke
				(width 0.1524)
				(type default)
			)
			(layer "F.SilkS")
		)
		(fp_line
			(start -0.7874 0.4064)
			(end -0.7874 -0.4064)
			(stroke
				(width 0.1524)
				(type default)
			)
			(layer "F.SilkS")
		)
		(fp_line
			(start 0.7874 -0.4064)
			(end 0.7874 0.4064)
			(stroke
				(width 0.1524)
				(type default)
			)
			(layer "F.SilkS")
		)
		(fp_line
			(start 0.7874 0.4064)
			(end -0.7874 0.4064)
			(stroke
				(width 0.1524)
				(type default)
			)
			(layer "F.SilkS")
		)
		(fp_line
			(start -0.67945 -0.305054)
			(end -0.12065 -0.305054)
			(stroke
				(width 0.1)
				(type default)
			)
			(layer "F.Fab")
		)
		(fp_line
			(start -0.67945 0.3048)
			(end -0.67945 -0.305054)
			(stroke
				(width 0.1)
				(type default)
			)
			(layer "F.Fab")
		)
		(fp_line
			(start -0.12065 -0.305054)
			(end -0.12065 -0.2794)
			(stroke
				(width 0.1)
				(type default)
			)
			(layer "F.Fab")
		)
		(fp_line
			(start -0.12065 -0.2794)
			(end 0.12065 -0.2794)
			(stroke
				(width 0.1)
				(type default)
			)
			(layer "F.Fab")
		)
		(fp_line
			(start -0.12065 0.2794)
			(end -0.12065 0.3048)
			(stroke
				(width 0.1)
				(type default)
			)
			(layer "F.Fab")
		)
		(fp_line
			(start -0.12065 0.3048)
			(end -0.67945 0.3048)
			(stroke
				(width 0.1)
				(type default)
			)
			(layer "F.Fab")
		)
		(fp_line
			(start 0.120396 0.2794)
			(end -0.12065 0.2794)
			(stroke
				(width 0.1)
				(type default)
			)
			(layer "F.Fab")
		)
		(fp_line
			(start 0.120396 0.3048)
			(end 0.120396 0.2794)
			(stroke
				(width 0.1)
				(type default)
			)
			(layer "F.Fab")
		)
		(fp_line
			(start 0.12065 -0.3048)
			(end 0.67945 -0.3048)
			(stroke
				(width 0.1)
				(type default)
			)
			(layer "F.Fab")
		)
		(fp_line
			(start 0.12065 -0.2794)
			(end 0.12065 -0.3048)
			(stroke
				(width 0.1)
				(type default)
			)
			(layer "F.Fab")
		)
		(fp_line
			(start 0.67945 -0.3048)
			(end 0.67945 0.3048)
			(stroke
				(width 0.1)
				(type default)
			)
			(layer "F.Fab")
		)
		(fp_line
			(start 0.67945 0.3048)
			(end 0.120396 0.3048)
			(stroke
				(width 0.1)
				(type default)
			)
			(layer "F.Fab")
		)
		(pad "1" smd circle
			(at -0.40005 0)
			(size 0 0)
			(layers "F.Cu" "F.Mask" "F.Paste")
			(net "P3V3_AUX")
		)
		(pad "2" smd circle
			(at 0.40005 0)
			(size 0 0)
			(layers "F.Cu" "F.Mask" "F.Paste")
			(net "P3V3_STBY_R")
		)
	)
)
